FILE_TYPE = MULTI_PHYS_TABLE;

PART 'M24128BWDW6TP'

{========================================================================================}
:VALUE            | PART_TYPE | MATERIAL | PART_NUMBER    = STANDARD | LIFECYCLE      | PART_NUMBER   | JEDEC_TYPE            | DESCRIPTION                   | MANUFTR | MANUF_PN         | RD_CMPLS_LVL | CMPLS_LVL | FROM_PJ      | CLASS | DIP_SMD | DATA                     | EE_CHECK_LIST | FP_ECN                   | PSL | CREATOR | STATUS | MSD  | ESD_CDM | ESD_HBM | ESD_MM | PIN_LENGTH_SHORT_PIN | PIN_LENGTH_LONG_PIN | CREATEDAY  ;
{========================================================================================}
 'M24128-BWDW6TP' | 'SMLF'    | 'IC'     | 'AKE30Z0K610'(!) = ''       | ''               | 'AKE30Z0K610' |'TSSOP8_0-65_3X4-4XG'| 'IC(8P)M24128-BWDW6TP(TSSOP)' | 'SGT'   | 'M24128-BWDW6TP' | 'EP'         | 'EP'      | 'S83-JOSEPH' | 'IC'  | ''      | 'SGT_M24128-BWDW6TP.pdf' | ''            | 'TSSOP8_Foortprint.docx' | ''  | ''      | ''     | 'NA' | 'NA'    | 'NA'    | 'NA'   | '0 MILS'             | '0 MILS'            | '20190828'
 'M24128-BWDW6TP' | 'SMLF'    | 'EMPTY'  | 'AKE30Z0K610'(!) = ''       | ''               | 'AKE30Z0K610' |'TSSOP8_0-65_3X4-4XG'| 'IC(8P)M24128-BWDW6TP(TSSOP)' | 'SGT'   | 'M24128-BWDW6TP' | 'EP'         | 'EP'      | 'S83-JOSEPH' | 'IC'  | ''      | 'SGT_M24128-BWDW6TP.pdf' | ''            | 'TSSOP8_Foortprint.docx' | ''  | ''      | ''     | 'NA' | 'NA'    | 'NA'    | 'NA'   | '0 MILS'             | '0 MILS'            | '20190828'

END_PART

END.

